FILE_TYPE = CONNECTIVITY;
{Allegro Design Entry HDL 17.2-2016 S081 (4005846) 1/11/2022}
"PAGE_NUMBER" = 74;
0"NC";
1"GND\g";
2"GND\g";
3"PVDD18_S5_P1\g";
4"PVDD18_S5_P1\g";
5"PVDD_33_S5\g";
6"GND\g";
%"Q_CAP"
"1","(-8550,3000)","0","pure_quanta","I1";
;
LOCATION"C2661"
$SEC"1"
CDS_SEC"1"
MATERIAL"X6S"
TOLERANCE"20%"
VALUE"22UF"
PART_NUMBER"CH622KMEB02"
VOLTAGE"4V"
PACK_TYPE"C0402"
CDS_LIB"pure_quanta";
"B"
$PN"2"6;
"A"
$PN"1"3;
%"Q_CAP"
"1","(-7650,3775)","0","pure_quanta","I10";
;
LOCATION"C2665"
$SEC"1"
CDS_SEC"1"
MATERIAL"X6S"
TOLERANCE"20%"
VALUE"22UF"
PART_NUMBER"CH622KMEB02"
VOLTAGE"4V"
PACK_TYPE"C0402"
CDS_LIB"pure_quanta";
"B"
$PN"2"1;
"A"
$PN"1"4;
%"Q_CAP"
"1","(-7200,3775)","0","pure_quanta","I11";
;
LOCATION"C2667"
$SEC"1"
CDS_SEC"1"
MATERIAL"X6S"
TOLERANCE"20%"
VALUE"22UF"
PART_NUMBER"CH622KMEB02"
VOLTAGE"4V"
PACK_TYPE"C0402"
CDS_LIB"pure_quanta";
"B"
$PN"2"1;
"A"
$PN"1"4;
%"Q_CAP"
"1","(-6750,3775)","0","pure_quanta","I12";
;
LOCATION"C2668"
$SEC"1"
CDS_SEC"1"
MATERIAL"X6S"
TOLERANCE"20%"
VALUE"22UF"
PART_NUMBER"CH622KMEB02"
VOLTAGE"4V"
PACK_TYPE"C0402"
CDS_LIB"pure_quanta";
"B"
$PN"2"1;
"A"
$PN"1"4;
%"Q_CAP"
"1","(-6300,3775)","0","pure_quanta","I13";
;
LOCATION"C2669"
$SEC"1"
CDS_SEC"1"
MATERIAL"X6S"
TOLERANCE"20%"
VALUE"22UF"
PART_NUMBER"CH622KMEB02"
VOLTAGE"4V"
PACK_TYPE"C0402"
CDS_LIB"pure_quanta";
"B"
$PN"2"1;
"A"
$PN"1"4;
%"Q_CAP"
"1","(-5850,3775)","0","pure_quanta","I14";
;
LOCATION"C2670"
$SEC"1"
CDS_SEC"1"
MATERIAL"X6S"
TOLERANCE"20%"
VALUE"22UF"
PART_NUMBER"CH622KMEB02"
VOLTAGE"4V"
PACK_TYPE"C0402"
CDS_LIB"pure_quanta";
"B"
$PN"2"1;
"A"
$PN"1"4;
%"Q_CAP"
"1","(-5400,3775)","0","pure_quanta","I15";
;
LOCATION"C2671"
$SEC"1"
CDS_SEC"1"
MATERIAL"X6S"
TOLERANCE"20%"
VALUE"22UF"
PART_NUMBER"CH622KMEB02"
VOLTAGE"4V"
PACK_TYPE"C0402"
CDS_LIB"pure_quanta";
"B"
$PN"2"1;
"A"
$PN"1"4;
%"Q_CAP"
"1","(-4950,3775)","0","pure_quanta","I16";
;
LOCATION"C2672"
$SEC"1"
CDS_SEC"1"
MATERIAL"X6S"
TOLERANCE"20%"
VALUE"22UF"
PART_NUMBER"CH622KMEB02"
VOLTAGE"4V"
PACK_TYPE"C0402"
CDS_LIB"pure_quanta";
"B"
$PN"2"1;
"A"
$PN"1"4;
%"UNIVERSAL_GND"
"1","(-4550,3400)","0","pure_quanta_power","I17";
;
CDS_LIB"pure_quanta_power"
HDL_POWER"GND";
"A"1;
%"Q_CAP"
"1","(-4550,3775)","0","pure_quanta","I18";
;
LOCATION"C2673"
$SEC"1"
CDS_SEC"1"
MATERIAL"X6S"
TOLERANCE"20%"
VALUE"22UF"
PART_NUMBER"CH622KMEB02"
VOLTAGE"4V"
PACK_TYPE"C0402"
CDS_LIB"pure_quanta";
"B"
$PN"2"1;
"A"
$PN"1"4;
%"UNIVERSAL_GND"
"1","(-8100,5025)","0","pure_quanta_power","I19";
;
CDS_LIB"pure_quanta_power"
HDL_POWER"GND";
"A"2;
%"UNIVERSAL_POWER"
"1","(-8550,3275)","0","pure_quanta_power","I2";
;
HDL_POWER"PVDD18_S5_P1"
CDS_LIB"pure_quanta_power";
"A"3;
%"Q_CAP"
"1","(-8100,5400)","0","pure_quanta","I20";
;
LOCATION"C2662"
$SEC"1"
CDS_SEC"1"
MATERIAL"X6S"
TOLERANCE"20%"
VALUE"22UF"
PART_NUMBER"CH622KMEB02"
VOLTAGE"4V"
PACK_TYPE"C0402"
CDS_LIB"pure_quanta";
"B"
$PN"2"2;
"A"
$PN"1"5;
%"Q_CAP"
"1","(-8550,3775)","0","pure_quanta","I3";
;
LOCATION"C2660"
$SEC"1"
CDS_SEC"1"
MATERIAL"X6S"
TOLERANCE"20%"
VALUE"22UF"
PART_NUMBER"CH622KMEB02"
VOLTAGE"4V"
PACK_TYPE"C0402"
CDS_LIB"pure_quanta";
"B"
$PN"2"1;
"A"
$PN"1"4;
%"UNIVERSAL_POWER"
"1","(-8550,4050)","0","pure_quanta_power","I4";
;
HDL_POWER"PVDD18_S5_P1"
CDS_LIB"pure_quanta_power";
"A"4;
%"Q_CAP"
"1","(-8550,5400)","0","pure_quanta","I5";
;
LOCATION"C2659"
$SEC"1"
CDS_SEC"1"
MATERIAL"X6S"
TOLERANCE"20%"
VALUE"22UF"
PART_NUMBER"CH622KMEB02"
VOLTAGE"4V"
PACK_TYPE"C0402"
CDS_LIB"pure_quanta";
"B"
$PN"2"2;
"A"
$PN"1"5;
%"UNIVERSAL_POWER"
"1","(-8550,5675)","0","pure_quanta_power","I6";
;
HDL_POWER"PVDD_33_S5"
CDS_LIB"pure_quanta_power";
"A"5;
%"UNIVERSAL_GND"
"1","(-8100,2625)","0","pure_quanta_power","I7";
;
CDS_LIB"pure_quanta_power"
HDL_POWER"GND";
"A"6;
%"Q_CAP"
"1","(-8100,3000)","0","pure_quanta","I8";
;
LOCATION"C2664"
$SEC"1"
CDS_SEC"1"
MATERIAL"X6S"
TOLERANCE"20%"
VALUE"22UF"
PART_NUMBER"CH622KMEB02"
VOLTAGE"4V"
PACK_TYPE"C0402"
CDS_LIB"pure_quanta";
"B"
$PN"2"6;
"A"
$PN"1"3;
%"Q_CAP"
"1","(-8100,3775)","0","pure_quanta","I9";
;
LOCATION"C2663"
$SEC"1"
CDS_SEC"1"
MATERIAL"X6S"
TOLERANCE"20%"
VALUE"22UF"
PART_NUMBER"CH622KMEB02"
VOLTAGE"4V"
PACK_TYPE"C0402"
CDS_LIB"pure_quanta";
"B"
$PN"2"1;
"A"
$PN"1"4;
END.
